# TIMECARD (Time Appliance Project (Time Card)) — schematic netlist excerpt (pin names and nets, part order shuffled) for the footprints in the layout excerpt that follows; sources: Cadence DE-HDL packaged netlist, KiCad conversion of R4006-B0001-02_R01.brd

J3  CONN_JACK_1P_GH4_S_TH  2081680-1  pkg P_F_JACK_1P_GH4_RA_P200  page 23
  \1\  = SMA1_SIG_IO_CONN
  GH1  = SG
  GH2  = SG
  GH3  = SG
  GH4  = SG

(kicad_pcb
	(version 20260206)
	(generator "pcbnew")
	(generator_version "10.0")
	(general
		(thickness 1.6)
		(legacy_teardrops no)
	)
	(paper "A4")
	(title_block
		(title "timecard-production-celestica-r4006 — R4006-B0001-02_R01.brd")
		(comment 1 "Time Appliance Project (Time Card) / footprints 193-193 of 1113")
	)
	(layers
		(0 "F.Cu" signal "TOP")
		(4 "In1.Cu" signal "L02_GND1")
		(6 "In2.Cu" signal "L03_SIG1")
		(8 "In3.Cu" signal "L04_GND2")
		(10 "In4.Cu" signal "L05_VCC1")
		(12 "In5.Cu" signal "L06_VCC2")
		(14 "In6.Cu" signal "L07_GND3")
		(16 "In7.Cu" signal "L08_SIG2")
		(18 "In8.Cu" signal "L09_GND4")
		(2 "B.Cu" signal "BOTTOM")
		(9 "F.Adhes" user "F.Adhesive")
		(11 "B.Adhes" user "B.Adhesive")
		(13 "F.Paste" user "Package Geometry/Pastemask Top")
		(15 "B.Paste" user "Package Geometry/Pastemask Bottom")
		(5 "F.SilkS" user "Ref Des/Silkscreen Top")
		(7 "B.SilkS" user "Ref Des/Silkscreen Bottom")
		(1 "F.Mask" user "Board Geometry/Soldermask Top")
		(3 "B.Mask" user "Board Geometry/Soldermask Bottom")
		(17 "Dwgs.User" user "User.Drawings")
		(19 "Cmts.User" user "User.Comments")
		(21 "Eco1.User" user "User.Eco1")
		(23 "Eco2.User" user "User.Eco2")
		(25 "Edge.Cuts" user "Board Geometry/Outline")
		(27 "Margin" user)
		(31 "F.CrtYd" user "Package Geometry/Place Bound Top")
		(29 "B.CrtYd" user "Package Geometry/Place Bound Bottom")
		(35 "F.Fab" user "Ref Des/Assembly Top")
		(33 "B.Fab" user "Ref Des/Assembly Bottom")
	)
	(footprint ""
		(layer "F.Cu")
		(at 4.073906 -61.60008)
		(property "Reference" "J3"
			(at 4.943094 -2.24155 0)
			(unlocked yes)
			(layer "F.SilkS")
			(effects
				(font
					(size 0.7874 0.5842)
					(thickness 0.1524)
				)
			)
		)
		(property "Value" ""
			(at 0 0 0)
			(layer "F.Fab")
			(effects
				(font
					(size 1.27 1.27)
				)
			)
		)
		(property "Device Type" "CONN_JACK_1P_GH4_S_TH-G200-130A"
			(at -5.098288 5.899912 0)
			(unlocked yes)
			(layer "F.Fab")
			(hide yes)
			(effects
				(font
					(size 0.7874 0.5842)
					(thickness 0.1524)
				)
			)
		)
		(property "User Part Number" "PARTNUM*"
			(at -5.098288 7.093712 0)
			(unlocked yes)
			(layer "Cmts.User")
			(hide yes)
			(effects
				(font
					(size 0.7874 0.5842)
					(thickness 0.1524)
				)
			)
		)
		(duplicate_pad_numbers_are_jumpers no)
		(fp_line
			(start -13.953998 -3.937)
			(end 3.937 -3.937)
			(stroke
				(width 0.1)
				(type default)
			)
			(layer "F.SilkS")
		)
		(fp_line
			(start -13.953998 3.937)
			(end -13.953998 -3.937)
			(stroke
				(width 0.1)
				(type default)
			)
			(layer "F.SilkS")
		)
		(fp_line
			(start 3.937 -3.937)
			(end 3.937 3.937)
			(stroke
				(width 0.1)
				(type default)
			)
			(layer "F.SilkS")
		)
		(fp_line
			(start 3.937 3.937)
			(end -13.953998 3.937)
			(stroke
				(width 0.1)
				(type default)
			)
			(layer "F.SilkS")
		)
		(fp_rect
			(start -8.763 8.763)
			(end 8.763 -8.763)
			(stroke
				(width 0)
				(type default)
			)
			(fill no)
			(layer "B.CrtYd")
		)
		(fp_rect
			(start -14.207998 4.191)
			(end 4.191 -4.191)
			(stroke
				(width 0)
				(type default)
			)
			(fill no)
			(layer "F.CrtYd")
		)
		(fp_line
			(start -13.699998 -3.599942)
			(end 3.599942 -3.599942)
			(stroke
				(width 0.1)
				(type default)
			)
			(layer "F.Fab")
		)
		(fp_line
			(start -13.699998 3.599942)
			(end -13.699998 -3.599942)
			(stroke
				(width 0.1)
				(type default)
			)
			(layer "F.Fab")
		)
		(fp_line
			(start 3.599942 -3.599942)
			(end 3.599942 3.599942)
			(stroke
				(width 0.1)
				(type default)
			)
			(layer "F.Fab")
		)
		(fp_line
			(start 3.599942 3.599942)
			(end -13.699998 3.599942)
			(stroke
				(width 0.1)
				(type default)
			)
			(layer "F.Fab")
		)
		(fp_text user "GH1"
			(at 0.117094 -4.28117 0)
			(unlocked yes)
			(layer "F.SilkS")
			(effects
				(font
					(size 0.635 0.4064)
					(thickness 0.1524)
				)
			)
		)
		(fp_text user "GH3"
			(at 0.752094 4.68503 0)
			(unlocked yes)
			(layer "F.SilkS")
			(effects
				(font
					(size 0.635 0.4064)
					(thickness 0.1524)
				)
			)
		)
		(fp_text user "GH2"
			(at 2.530094 -4.28117 0)
			(unlocked yes)
			(layer "F.SilkS")
			(effects
				(font
					(size 0.635 0.4064)
					(thickness 0.1524)
				)
			)
		)
		(fp_text user "GH4"
			(at 3.038094 4.68503 0)
			(unlocked yes)
			(layer "F.SilkS")
			(effects
				(font
					(size 0.635 0.4064)
					(thickness 0.1524)
				)
			)
		)
		(fp_text user "1"
			(at 4.191 -0.35433 0)
			(unlocked yes)
			(layer "F.SilkS")
			(effects
				(font
					(size 0.7874 0.5842)
					(thickness 0.1524)
				)
				(justify left)
			)
		)
		(fp_text user "GH1"
			(at -2.549906 -4.14655 0)
			(unlocked yes)
			(layer "F.Fab")
			(effects
				(font
					(size 0.7874 0.5842)
					(thickness 0.1524)
				)
			)
		)
		(fp_text user "GH3"
			(at -2.422906 4.229608 0)
			(unlocked yes)
			(layer "F.Fab")
			(effects
				(font
					(size 0.7874 0.5842)
					(thickness 0.1524)
				)
			)
		)
		(fp_text user "GH4"
			(at 2.403094 4.229608 0)
			(unlocked yes)
			(layer "F.Fab")
			(effects
				(font
					(size 0.7874 0.5842)
					(thickness 0.1524)
				)
			)
		)
		(fp_text user "GH2"
			(at 2.54 -4.57073 0)
			(unlocked yes)
			(layer "F.Fab")
			(effects
				(font
					(size 0.7874 0.5842)
					(thickness 0.1524)
				)
			)
		)
		(fp_text user "1"
			(at 4.191 -0.35433 0)
			(unlocked yes)
			(layer "F.Fab")
			(effects
				(font
					(size 0.7874 0.5842)
					(thickness 0.1524)
				)
				(justify left)
			)
		)
		(pad "1" thru_hole circle
			(at 0 0)
			(size 2.1844 2.1844)
			(drill 1.4986)
			(layers "*.Cu" "*.Mask")
			(remove_unused_layers no)
			(net "SMA1_SIG_IO_CONN")
			(padstack
				(mode front_inner_back)
				(layer "Inner"
					(shape circle)
					(size 2.1844 2.1844)
					(clearance -0.0508)
				)
				(layer "B.Cu"
					(shape circle)
					(size 2.1844 2.1844)
				)
			)
		)
		(pad "GH1" thru_hole circle
			(at -2.54 -2.54)
			(size 2.286 2.286)
			(drill 1.6002)
			(layers "*.Cu" "*.Mask")
			(remove_unused_layers no)
			(net "SG")
			(padstack
				(mode front_inner_back)
				(layer "Inner"
					(shape circle)
					(size 2.286 2.286)
					(clearance -0.0508)
				)
				(layer "B.Cu"
					(shape circle)
					(size 2.286 2.286)
				)
			)
		)
		(pad "GH2" thru_hole circle
			(at 2.54 -2.54)
			(size 2.286 2.286)
			(drill 1.6002)
			(layers "*.Cu" "*.Mask")
			(remove_unused_layers no)
			(net "SG")
			(padstack
				(mode front_inner_back)
				(layer "Inner"
					(shape circle)
					(size 2.286 2.286)
					(clearance -0.0508)
				)
				(layer "B.Cu"
					(shape circle)
					(size 2.286 2.286)
				)
			)
		)
		(pad "GH3" thru_hole circle
			(at -2.54 2.54)
			(size 2.286 2.286)
			(drill 1.6002)
			(layers "*.Cu" "*.Mask")
			(remove_unused_layers no)
			(net "SG")
			(padstack
				(mode front_inner_back)
				(layer "Inner"
					(shape circle)
					(size 2.286 2.286)
					(clearance -0.0508)
				)
				(layer "B.Cu"
					(shape circle)
					(size 2.286 2.286)
				)
			)
		)
		(pad "GH4" thru_hole circle
			(at 2.54 2.54)
			(size 2.286 2.286)
			(drill 1.6002)
			(layers "*.Cu" "*.Mask")
			(remove_unused_layers no)
			(net "SG")
			(padstack
				(mode front_inner_back)
				(layer "Inner"
					(shape circle)
					(size 2.286 2.286)
					(clearance -0.0508)
				)
				(layer "B.Cu"
					(shape circle)
					(size 2.286 2.286)
				)
			)
		)
	)
)
